(kicad_pcb
	(version 20211014)
	(generator pcbnew)
	(general
    (thickness 1.6)
  )
	(paper "A4")
	(title_block
    (title "SA800U (Snapdragon 845) Baseboard")
    (date "2023-10-19")
    (rev "1.0.3")
    (company "Antmicro Ltd.")
    (comment 1 "www.antmicro.com")
		(comment 9 "footprints 144-149 of 589")
	)
	(layers
    (0 "F.Cu" signal)
    (1 "In1.Cu" power)
    (2 "In2.Cu" signal)
    (3 "In3.Cu" signal)
    (4 "In4.Cu" power)
    (31 "B.Cu" signal)
    (32 "B.Adhes" user "B.Adhesive")
    (33 "F.Adhes" user "F.Adhesive")
    (34 "B.Paste" user)
    (35 "F.Paste" user)
    (36 "B.SilkS" user "B.Silkscreen")
    (37 "F.SilkS" user "F.Silkscreen")
    (38 "B.Mask" user)
    (39 "F.Mask" user)
    (40 "Dwgs.User" user "User.Drawings")
    (41 "Cmts.User" user "User.Comments")
    (42 "Eco1.User" user "User.Eco1")
    (43 "Eco2.User" user "User.Eco2")
    (44 "Edge.Cuts" user)
    (45 "Margin" user)
    (46 "B.CrtYd" user "B.Courtyard")
    (47 "F.CrtYd" user "F.Courtyard")
    (48 "B.Fab" user)
    (49 "F.Fab" user)
  )
	(footprint "sa800u-baseboard-hw-footprints:QFN-24-1EP_4x4mm_EP2.1x2.1mm" (layer "F.Cu")
    (tedit 5DC5F6A3)
    (at 75.25 124.4 180)
    (descr "QFN, 24 Pin")
    (tags "QFN NoLead")
    (property "Author" "Antmicro")
    (property "License" "Apache-2.0")
    (property "MPN" "LTC4417IUF#TRPBF")
    (property "Manufacturer" "Analog Devices")
    (property "Sheetfile" "psu.kicad_sch")
    (property "Sheetname" "PSU")
    (attr smd)
    (fp_text reference "U17" (at 4.34 -2.47 180) (layer "F.SilkS")
      (effects (font (size 0.7 0.7) (thickness 0.15)) (justify left bottom))
    )
    (fp_text value "LTC4417_QFN" (at 0 3.4 180) (layer "F.Fab")
      (effects (font (size 0.7 0.7) (thickness 0.15)) (justify left bottom))
    )
    (fp_text user "Author: Antmicro" (at -2.503 7.8 180) (layer "F.Fab") hide
      (effects (font (size 0.7 0.7) (thickness 0.15)) (justify left bottom))
    )
    (fp_text user "${REFERENCE}" (at -2.503 5.4 180) (layer "F.Fab") hide
      (effects (font (size 0.7 0.7) (thickness 0.15)) (justify left bottom))
    )
    (fp_text user "License: Apache-2.0" (at -2.503 6.6 180) (layer "F.Fab") hide
      (effects (font (size 0.7 0.7) (thickness 0.15)) (justify left bottom))
    )
    (fp_line (start -1.635 2.108) (end -2.11 2.108) (layer "F.SilkS") (width 0.15))
    (fp_line (start 2.108 2.108) (end 2.108 1.634) (layer "F.SilkS") (width 0.15))
    (fp_line (start 1.634 -2.11) (end 2.108 -2.11) (layer "F.SilkS") (width 0.15))
    (fp_line (start -2.11 -1.636) (end -2.11 -2.11) (layer "F.SilkS") (width 0.15))
    (fp_line (start 2.108 -2.11) (end 2.108 -1.635) (layer "F.SilkS") (width 0.15))
    (fp_line (start -2.11 2.108) (end -2.11 1.634) (layer "F.SilkS") (width 0.15))
    (fp_line (start -1.635 -2.11) (end -2.11 -2.11) (layer "F.SilkS") (width 0.15))
    (fp_line (start 1.634 2.108) (end 2.108 2.108) (layer "F.SilkS") (width 0.15))
    (fp_circle (center -2.3 -2.3) (end -2.25 -2.3) (layer "F.SilkS") (width 0.15) (fill solid))
    (fp_rect (start -2.503 -2.503) (end 2.5 2.5) (layer "F.CrtYd") (width 0.05) (fill none))
    (fp_line (start 1.999 1.999) (end -2 1.999) (layer "F.Fab") (width 0.15))
    (fp_line (start 1.999 -2) (end 1.999 1.999) (layer "F.Fab") (width 0.15))
    (fp_line (start -2 1.999) (end -2 -1) (layer "F.Fab") (width 0.15))
    (fp_line (start -1 -2) (end 1.999 -2) (layer "F.Fab") (width 0.15))
    (fp_line (start -2 -1) (end -1 -2) (layer "F.Fab") (width 0.15))
    (pad "" smd roundrect (at -0.5 -0.5 180) (size 0.8 0.8) (layers "F.Paste") (roundrect_rratio 0.238095))
    (pad "" smd roundrect (at 0.5 -0.5 180) (size 0.8 0.8) (layers "F.Paste") (roundrect_rratio 0.238095))
    (pad "" smd roundrect (at -0.5 0.5 180) (size 0.8 0.8) (layers "F.Paste") (roundrect_rratio 0.238095))
    (pad "" smd roundrect (at 0.5 0.5 180) (size 0.8 0.8) (layers "F.Paste") (roundrect_rratio 0.238095))
    (pad "1" smd roundrect (at -1.938 -1.25 180) (size 0.825 0.25) (layers "F.Cu" "F.Paste" "F.Mask") (roundrect_rratio 0.25)
      (net 402 "Net-(R112-Pad2)") (pinfunction "UV1") (pintype "input"))
    (pad "2" smd roundrect (at -1.938 -0.75 180) (size 0.825 0.25) (layers "F.Cu" "F.Paste" "F.Mask") (roundrect_rratio 0.25)
      (net 403 "Net-(R113-Pad2)") (pinfunction "OV1") (pintype "input"))
    (pad "3" smd roundrect (at -1.938 -0.25 180) (size 0.825 0.25) (layers "F.Cu" "F.Paste" "F.Mask") (roundrect_rratio 0.25)
      (net 401 "Net-(R108-Pad2)") (pinfunction "UV2") (pintype "input"))
    (pad "4" smd roundrect (at -1.938 0.248 180) (size 0.825 0.25) (layers "F.Cu" "F.Paste" "F.Mask") (roundrect_rratio 0.25)
      (net 128 "Net-(R109-Pad2)") (pinfunction "OV2") (pintype "input"))
    (pad "5" smd roundrect (at -1.938 0.748 180) (size 0.825 0.25) (layers "F.Cu" "F.Paste" "F.Mask") (roundrect_rratio 0.25)
      (net 399 "Net-(R105-Pad2)") (pinfunction "UV3") (pintype "input"))
    (pad "6" smd roundrect (at -1.938 1.249 180) (size 0.825 0.25) (layers "F.Cu" "F.Paste" "F.Mask") (roundrect_rratio 0.25)
      (net 400 "Net-(R106-Pad2)") (pinfunction "OV3") (pintype "input"))
    (pad "7" smd roundrect (at -1.25 1.937 180) (size 0.25 0.825) (layers "F.Cu" "F.Paste" "F.Mask") (roundrect_rratio 0.25)
      (net 339 "/PSU/AUX_VALID") (pinfunction "~{VALID1}") (pintype "output"))
    (pad "8" smd roundrect (at -0.75 1.937 180) (size 0.25 0.825) (layers "F.Cu" "F.Paste" "F.Mask") (roundrect_rratio 0.25)
      (net 341 "/PSU/USB_PD_VALID") (pinfunction "~{VALID2}") (pintype "output"))
    (pad "9" smd roundrect (at -0.25 1.937 180) (size 0.25 0.825) (layers "F.Cu" "F.Paste" "F.Mask") (roundrect_rratio 0.25)
      (net 340 "/PSU/POE_VALID") (pinfunction "~{VALID3}") (pintype "output"))
    (pad "10" smd roundrect (at 0.248 1.937 180) (size 0.25 0.825) (layers "F.Cu" "F.Paste" "F.Mask") (roundrect_rratio 0.25)
      (net 1 "GND") (pinfunction "GND") (pintype "power_in"))
    (pad "11" smd roundrect (at 0.748 1.937 180) (size 0.25 0.825) (layers "F.Cu" "F.Paste" "F.Mask") (roundrect_rratio 0.25)
      (net 659 "unconnected-(U17-Pad11)") (pinfunction "CAS") (pintype "output+no_connect"))
    (pad "12" smd roundrect (at 1.249 1.937 180) (size 0.25 0.825) (layers "F.Cu" "F.Paste" "F.Mask") (roundrect_rratio 0.25)
      (net 74 "VDD") (pinfunction "VOUT") (pintype "output"))
    (pad "13" smd roundrect (at 1.937 1.249 180) (size 0.825 0.25) (layers "F.Cu" "F.Paste" "F.Mask") (roundrect_rratio 0.25)
      (net 367 "/PSU/G3") (pinfunction "G3") (pintype "output"))
    (pad "14" smd roundrect (at 1.937 0.748 180) (size 0.825 0.25) (layers "F.Cu" "F.Paste" "F.Mask") (roundrect_rratio 0.25)
      (net 159 "/PSU/VS3") (pinfunction "VS3") (pintype "unspecified"))
    (pad "15" smd roundrect (at 1.937 0.248 180) (size 0.825 0.25) (layers "F.Cu" "F.Paste" "F.Mask") (roundrect_rratio 0.25)
      (net 355 "/PSU/G2") (pinfunction "G2") (pintype "output"))
    (pad "16" smd roundrect (at 1.937 -0.25 180) (size 0.825 0.25) (layers "F.Cu" "F.Paste" "F.Mask") (roundrect_rratio 0.25)
      (net 158 "/PSU/VS2") (pinfunction "VS2") (pintype "unspecified"))
    (pad "17" smd roundrect (at 1.937 -0.75 180) (size 0.825 0.25) (layers "F.Cu" "F.Paste" "F.Mask") (roundrect_rratio 0.25)
      (net 354 "/PSU/G1") (pinfunction "G1") (pintype "output"))
    (pad "18" smd roundrect (at 1.937 -1.25 180) (size 0.825 0.25) (layers "F.Cu" "F.Paste" "F.Mask") (roundrect_rratio 0.25)
      (net 157 "/PSU/VS1") (pinfunction "VS1") (pintype "unspecified"))
    (pad "19" smd roundrect (at 1.249 -1.938 180) (size 0.25 0.825) (layers "F.Cu" "F.Paste" "F.Mask") (roundrect_rratio 0.25)
      (net 136 "5V_POE") (pinfunction "V3") (pintype "input"))
    (pad "20" smd roundrect (at 0.748 -1.938 180) (size 0.25 0.825) (layers "F.Cu" "F.Paste" "F.Mask") (roundrect_rratio 0.25)
      (net 142 "PD_VDD") (pinfunction "V2") (pintype "input"))
    (pad "21" smd roundrect (at 0.248 -1.938 180) (size 0.25 0.825) (layers "F.Cu" "F.Paste" "F.Mask") (roundrect_rratio 0.25)
      (net 152 "/PSU/AUX_VDD") (pinfunction "V1") (pintype "input"))
    (pad "22" smd roundrect (at -0.25 -1.938 180) (size 0.25 0.825) (layers "F.Cu" "F.Paste" "F.Mask") (roundrect_rratio 0.25)
      (net 658 "unconnected-(U17-Pad22)") (pinfunction "EN") (pintype "input+no_connect"))
    (pad "23" smd roundrect (at -0.75 -1.938 180) (size 0.25 0.825) (layers "F.Cu" "F.Paste" "F.Mask") (roundrect_rratio 0.25)
      (net 657 "unconnected-(U17-Pad23)") (pinfunction "~{SHDN}") (pintype "input+no_connect"))
    (pad "24" smd roundrect (at -1.25 -1.938 180) (size 0.25 0.825) (layers "F.Cu" "F.Paste" "F.Mask") (roundrect_rratio 0.25)
      (net 404 "Net-(R117-Pad1)") (pinfunction "HYS") (pintype "input"))
    (pad "25" smd rect (at 0 0 180) (size 2.1 2.1) (layers "F.Cu" "F.Mask")
      (net 1 "GND") (pinfunction "EPAD") (pintype "unspecified"))
  )
	(footprint "sa800u-baseboard-hw-footprints:R_0402_1005Metric" (layer "F.Cu")
    (tedit 5FD9C158)
    (at 90.75 130.5)
    (descr "Resistor SMD 0402")
    (tags "resistor SMD 0402")
    (property "Author" "Antmicro")
    (property "License" "Apache-2.0")
    (property "MPN" "CR0402-FX-2701GLF")
    (property "Manufacturer" "Bourns")
    (property "Sheetfile" "usb-pd.kicad_sch")
    (property "Sheetname" "USB-PD")
    (property "Tolerance" "1%")
    (property "Val" "2k7")
    (attr smd)
    (fp_text reference "R174" (at -3.56 0.31) (layer "F.SilkS")
      (effects (font (size 0.7 0.7) (thickness 0.15)) (justify left bottom))
    )
    (fp_text value "R_2k7_0402" (at 0 1.4) (layer "F.Fab")
      (effects (font (size 0.7 0.7) (thickness 0.15)) (justify left bottom))
    )
    (fp_text user "${REFERENCE}" (at -0.95 3.168) (layer "F.Fab") hide
      (effects (font (size 0.7 0.7) (thickness 0.15)) (justify left bottom))
    )
    (fp_text user "License: Apache-2.0" (at -0.95 5.169) (layer "F.Fab") hide
      (effects (font (size 0.7 0.7) (thickness 0.15)) (justify left bottom))
    )
    (fp_text user "Author: Antmicro" (at -0.95 4.169) (layer "F.Fab") hide
      (effects (font (size 0.7 0.7) (thickness 0.15)) (justify left bottom))
    )
    (fp_rect (start -0.93 -0.47) (end 0.93 0.47) (layer "F.CrtYd") (width 0.05) (fill none))
    (fp_rect (start -0.5 -0.25) (end 0.5 0.25) (layer "F.Fab") (width 0.15) (fill none))
    (pad "1" smd roundrect (at -0.485 0) (size 0.59 0.64) (layers "F.Cu" "F.Paste" "F.Mask") (roundrect_rratio 0.25)
      (net 142 "PD_VDD") (pintype "passive"))
    (pad "2" smd roundrect (at 0.485 0) (size 0.59 0.64) (layers "F.Cu" "F.Paste" "F.Mask") (roundrect_rratio 0.25)
      (net 383 "Net-(D36-Pad4)") (pintype "passive"))
  )
	(footprint "sa800u-baseboard-hw-footprints:R_0402_1005Metric" (layer "F.Cu")
    (tedit 5FD9C158)
    (at 90.75 131.55)
    (descr "Resistor SMD 0402")
    (tags "resistor SMD 0402")
    (property "Author" "Antmicro")
    (property "License" "Apache-2.0")
    (property "MPN" "CR0402-FX-7500GLF")
    (property "Manufacturer" "Bourns")
    (property "Sheetfile" "usb-pd.kicad_sch")
    (property "Sheetname" "USB-PD")
    (property "Tolerance" "1%")
    (property "Val" "750R")
    (attr smd)
    (fp_text reference "R173" (at -3.56 0.31) (layer "F.SilkS")
      (effects (font (size 0.7 0.7) (thickness 0.15)) (justify left bottom))
    )
    (fp_text value "R_750R_0402" (at 0 1.4) (layer "F.Fab")
      (effects (font (size 0.7 0.7) (thickness 0.15)) (justify left bottom))
    )
    (fp_text user "${REFERENCE}" (at -0.95 3.168) (layer "F.Fab") hide
      (effects (font (size 0.7 0.7) (thickness 0.15)) (justify left bottom))
    )
    (fp_text user "Author: Antmicro" (at -0.95 4.169) (layer "F.Fab") hide
      (effects (font (size 0.7 0.7) (thickness 0.15)) (justify left bottom))
    )
    (fp_text user "License: Apache-2.0" (at -0.95 5.169) (layer "F.Fab") hide
      (effects (font (size 0.7 0.7) (thickness 0.15)) (justify left bottom))
    )
    (fp_rect (start -0.93 -0.47) (end 0.93 0.47) (layer "F.CrtYd") (width 0.05) (fill none))
    (fp_rect (start -0.5 -0.25) (end 0.5 0.25) (layer "F.Fab") (width 0.15) (fill none))
    (pad "1" smd roundrect (at -0.485 0) (size 0.59 0.64) (layers "F.Cu" "F.Paste" "F.Mask") (roundrect_rratio 0.25)
      (net 133 "5V_SYS") (pintype "passive"))
    (pad "2" smd roundrect (at 0.485 0) (size 0.59 0.64) (layers "F.Cu" "F.Paste" "F.Mask") (roundrect_rratio 0.25)
      (net 382 "Net-(D36-Pad5)") (pintype "passive"))
  )
	(footprint "sa800u-baseboard-hw-footprints:PLCC6_3.5x3.7mm" (layer "F.Cu")
    (tedit 6215DBD2)
    (at 94.3 131.6 180)
    (property "Author" "Antmicro")
    (property "License" "Apache-2.0")
    (property "MPN" "ASMB-TTF0-0A20B")
    (property "Manufacturer" "Broadcom")
    (property "Sheetfile" "usb-pd.kicad_sch")
    (property "Sheetname" "USB-PD")
    (attr smd)
    (fp_text reference "D36" (at 0.22 -2.74 180) (layer "F.SilkS")
      (effects (font (size 0.7 0.7) (thickness 0.15)) (justify left bottom))
    )
    (fp_text value "ASMB-TTF0-0A20B" (at 0 -2.5 180) (layer "F.Fab")
      (effects (font (size 0.7 0.7) (thickness 0.15)) (justify left bottom))
    )
    (fp_text user "License: Apache-2.0" (at -2.5 8.573 180) (layer "F.Fab") hide
      (effects (font (size 0.7 0.7) (thickness 0.15)) (justify left bottom))
    )
    (fp_text user "${REFERENCE}" (at -2.5 4.974 180) (layer "F.Fab") hide
      (effects (font (size 0.7 0.7) (thickness 0.15)) (justify left bottom))
    )
    (fp_text user "Author: Antmicro" (at -2.5 6.174 180) (layer "F.Fab") hide
      (effects (font (size 0.7 0.7) (thickness 0.15)) (justify left bottom))
    )
    (fp_line (start -1.851 -1.696) (end 1.85 -1.696) (layer "F.SilkS") (width 0.15))
    (fp_line (start 1.85 1.804) (end -1.851 1.804) (layer "F.SilkS") (width 0.15))
    (fp_line (start -0.5 0.053) (end 0.348 -0.446) (layer "F.SilkS") (width 0.15))
    (fp_line (start 1.85 -1.696) (end 1.85 -1.496) (layer "F.SilkS") (width 0.15))
    (fp_line (start 1.85 1.804) (end 1.85 1.604) (layer "F.SilkS") (width 0.15))
    (fp_line (start -1.851 -1.696) (end -1.851 -1.496) (layer "F.SilkS") (width 0.15))
    (fp_line (start -0.5 -0.446) (end -0.5 0.552) (layer "F.SilkS") (width 0.15))
    (fp_line (start -1.805 -1.647) (end -1.754 -1.647) (layer "F.SilkS") (width 0.15))
    (fp_line (start -1.851 1.804) (end -1.851 1.604) (layer "F.SilkS") (width 0.15))
    (fp_line (start 0.348 0.552) (end -0.5 0.002) (layer "F.SilkS") (width 0.15))
    (fp_line (start 0.348 -0.446) (end 0.348 0.552) (layer "F.SilkS") (width 0.15))
    (fp_line (start -1.851 -1.496) (end -1.651 -1.7) (layer "F.SilkS") (width 0.15))
    (fp_line (start -2.4 -1.696) (end -2.4 1.804) (layer "F.SilkS") (width 0.15))
    (fp_circle (center -2.15 -1.65) (end -2.1 -1.65) (layer "F.SilkS") (width 0.15) (fill solid))
    (fp_rect (start -2.4 -2) (end 2.4 2.05) (layer "F.CrtYd") (width 0.05) (fill none))
    (fp_line (start -1.601 -1.7) (end -1.855 -1.47) (layer "F.Fab") (width 0.15))
    (fp_line (start -1.855 -1.47) (end -1.855 1.804) (layer "F.Fab") (width 0.15))
    (fp_line (start 1.854 1.804) (end -1.855 1.804) (layer "F.Fab") (width 0.15))
    (fp_line (start 1.854 -1.7) (end -1.601 -1.7) (layer "F.Fab") (width 0.15))
    (fp_line (start 1.854 -1.7) (end 1.854 1.804) (layer "F.Fab") (width 0.15))
    (pad "1" smd rect (at -1.5 -0.996 180) (size 1.6 0.7) (layers "F.Cu" "F.Paste" "F.Mask")
      (net 169 "/USB-PD/STUSB4500_PWR_OK2") (pinfunction "1") (pintype "passive"))
    (pad "2" smd rect (at -1.5 0.053 180) (size 1.6 0.7) (layers "F.Cu" "F.Paste" "F.Mask")
      (net 170 "/USB-PD/STUSB4500_PWR_OK3") (pinfunction "2") (pintype "passive"))
    (pad "3" smd rect (at -1.5 1.104 180) (size 1.6 0.7) (layers "F.Cu" "F.Paste" "F.Mask")
      (net 1 "GND") (pinfunction "3") (pintype "passive"))
    (pad "4" smd rect (at 1.499 1.104 180) (size 1.6 0.7) (layers "F.Cu" "F.Paste" "F.Mask")
      (net 383 "Net-(D36-Pad4)") (pinfunction "4") (pintype "passive"))
    (pad "5" smd rect (at 1.499 0.053 180) (size 1.6 0.7) (layers "F.Cu" "F.Paste" "F.Mask")
      (net 382 "Net-(D36-Pad5)") (pinfunction "5") (pintype "passive"))
    (pad "6" smd rect (at 1.499 -0.996 180) (size 1.6 0.7) (layers "F.Cu" "F.Paste" "F.Mask")
      (net 381 "Net-(D36-Pad6)") (pinfunction "6") (pintype "passive"))
  )
	(footprint "sa800u-baseboard-hw-footprints:R_0402_1005Metric" (layer "F.Cu")
    (tedit 5FD9C158)
    (at 79.9 121.9)
    (descr "Resistor SMD 0402")
    (tags "resistor SMD 0402")
    (property "Author" "Antmicro")
    (property "License" "Apache-2.0")
    (property "MPN" "CR0402-FX-1372GLF")
    (property "Manufacturer" "Bourns")
    (property "Sheetfile" "psu.kicad_sch")
    (property "Sheetname" "PSU")
    (property "Tolerance" "1%")
    (property "Val" "13k7")
    (attr smd)
    (fp_text reference "R107" (at -1.22 6.34) (layer "F.SilkS")
      (effects (font (size 0.7 0.7) (thickness 0.15)) (justify left bottom))
    )
    (fp_text value "R_13k7_0402" (at 0 1.4) (layer "F.Fab")
      (effects (font (size 0.7 0.7) (thickness 0.15)) (justify left bottom))
    )
    (fp_text user "${REFERENCE}" (at -0.95 3.168) (layer "F.Fab") hide
      (effects (font (size 0.7 0.7) (thickness 0.15)) (justify left bottom))
    )
    (fp_text user "License: Apache-2.0" (at -0.95 5.169) (layer "F.Fab") hide
      (effects (font (size 0.7 0.7) (thickness 0.15)) (justify left bottom))
    )
    (fp_text user "Author: Antmicro" (at -0.95 4.169) (layer "F.Fab") hide
      (effects (font (size 0.7 0.7) (thickness 0.15)) (justify left bottom))
    )
    (fp_rect (start -0.93 -0.47) (end 0.93 0.47) (layer "F.CrtYd") (width 0.05) (fill none))
    (fp_rect (start -0.5 -0.25) (end 0.5 0.25) (layer "F.Fab") (width 0.15) (fill none))
    (pad "1" smd roundrect (at -0.485 0) (size 0.59 0.64) (layers "F.Cu" "F.Paste" "F.Mask") (roundrect_rratio 0.25)
      (net 400 "Net-(R106-Pad2)") (pintype "passive"))
    (pad "2" smd roundrect (at 0.485 0) (size 0.59 0.64) (layers "F.Cu" "F.Paste" "F.Mask") (roundrect_rratio 0.25)
      (net 1 "GND") (pintype "passive"))
  )
	(footprint "sa800u-baseboard-hw-footprints:R_0402_1005Metric" (layer "F.Cu")
    (tedit 5FD9C158)
    (at 79.9 123.9)
    (descr "Resistor SMD 0402")
    (tags "resistor SMD 0402")
    (property "Author" "Antmicro")
    (property "License" "Apache-2.0")
    (property "MPN" "CR0402-FX-1372GLF")
    (property "Manufacturer" "Bourns")
    (property "Sheetfile" "psu.kicad_sch")
    (property "Sheetname" "PSU")
    (property "Tolerance" "1%")
    (property "Val" "13k7")
    (attr smd)
    (fp_text reference "R110" (at -1.22 6.27) (layer "F.SilkS")
      (effects (font (size 0.7 0.7) (thickness 0.15)) (justify left bottom))
    )
    (fp_text value "R_13k7_0402" (at 0 1.4) (layer "F.Fab")
      (effects (font (size 0.7 0.7) (thickness 0.15)) (justify left bottom))
    )
    (fp_text user "Author: Antmicro" (at -0.95 4.169) (layer "F.Fab") hide
      (effects (font (size 0.7 0.7) (thickness 0.15)) (justify left bottom))
    )
    (fp_text user "${REFERENCE}" (at -0.95 3.168) (layer "F.Fab") hide
      (effects (font (size 0.7 0.7) (thickness 0.15)) (justify left bottom))
    )
    (fp_text user "License: Apache-2.0" (at -0.95 5.169) (layer "F.Fab") hide
      (effects (font (size 0.7 0.7) (thickness 0.15)) (justify left bottom))
    )
    (fp_rect (start -0.93 -0.47) (end 0.93 0.47) (layer "F.CrtYd") (width 0.05) (fill none))
    (fp_rect (start -0.5 -0.25) (end 0.5 0.25) (layer "F.Fab") (width 0.15) (fill none))
    (pad "1" smd roundrect (at -0.485 0) (size 0.59 0.64) (layers "F.Cu" "F.Paste" "F.Mask") (roundrect_rratio 0.25)
      (net 128 "Net-(R109-Pad2)") (pintype "passive"))
    (pad "2" smd roundrect (at 0.485 0) (size 0.59 0.64) (layers "F.Cu" "F.Paste" "F.Mask") (roundrect_rratio 0.25)
      (net 1 "GND") (pintype "passive"))
  )
)
